#ISCELL
  mstr_misc dns *
  *
#ISCELL
  pure_quanta quanta_title_block_c *
  *
#ISCELL
  standard offpage *
  page20_i1
#ISCELL
  standard offpage *
  page20_i10
#ISCELL
  standard offpage *
  page20_i100
#ISCELL
  standard offpage *
  page20_i101
#ISCELL
  standard offpage *
  page20_i102
#ISCELL
  standard offpage *
  page20_i103
#ISCELL
  standard offpage *
  page20_i104
#ISCELL
  standard offpage *
  page20_i105
#CELL
  pure_quanta q_cap *
  page20_i106
#CELL
  pure_quanta q_cap *
  page20_i107
#ISCELL
  logical_power universal_gnd *
  page20_i108
#ISCELL
  logical_power universal_gnd *
  page20_i109
#ISCELL
  standard offpage *
  page20_i11
#ISCELL
  logical_power universal_power *
  page20_i110
#CELL
  pure_quanta q_res *
  page20_i111
#ISCELL
  logical_power universal_gnd *
  page20_i112
#CELL
  pure_quanta q_cap *
  page20_i113
#CELL
  pure_quanta q_res *
  page20_i114
#CELL
  pure_quanta q_res *
  page20_i115
#CELL
  pure_quanta q_res *
  page20_i116
#CELL
  pure_quanta q_res *
  page20_i117
#CELL
  pure_quanta q_res *
  page20_i118
#CELL
  pure_quanta q_res *
  page20_i119
#ISCELL
  standard offpage *
  page20_i12
#CELL
  pure_quanta q_res *
  page20_i120
#CELL
  pure_quanta q_res *
  page20_i121
#CELL
  pure_quanta q_res *
  page20_i122
#CELL
  pure_quanta q_res *
  page20_i123
#CELL
  pure_quanta q_res *
  page20_i124
#CELL
  pure_quanta q_res *
  page20_i125
#ISCELL
  logical_power universal_gnd *
  page20_i126
#CELL
  pure_quanta q_res *
  page20_i127
#CELL
  pure_quanta q_res *
  page20_i128
#CELL
  pure_quanta q_res *
  page20_i129
#CELL
  pure_quanta q_res *
  page20_i13
#CELL
  pure_quanta q_res *
  page20_i130
#CELL
  pure_quanta q_res *
  page20_i131
#CELL
  pure_quanta q_res *
  page20_i132
#ISCELL
  logical_power universal_gnd *
  page20_i133
#CELL
  pure_quanta q_cap *
  page20_i134
#CELL
  pure_quanta q_res *
  page20_i135
#CELL
  pure_quanta q_res *
  page20_i136
#CELL
  pure_quanta q_res *
  page20_i137
#CELL
  pure_quanta q_res *
  page20_i138
#ISCELL
  logical_power universal_power *
  page20_i139
#CELL
  pure_quanta q_res *
  page20_i14
#ISCELL
  logical_power universal_power *
  page20_i140
#CELL
  pure_quanta q_res *
  page20_i141
#CELL
  pure_quanta q_res *
  page20_i142
#CELL
  pure_quanta q_res *
  page20_i143
#ISCELL
  standard tap *
  page20_i144
#ISCELL
  standard tap *
  page20_i145
#ISCELL
  standard tap *
  page20_i146
#ISCELL
  standard tap *
  page20_i147
#ISCELL
  standard tap *
  page20_i148
#ISCELL
  standard tap *
  page20_i149
#ISCELL
  logical_power universal_gnd *
  page20_i15
#ISCELL
  standard tap *
  page20_i150
#ISCELL
  standard tap *
  page20_i151
#ISCELL
  standard tap *
  page20_i152
#ISCELL
  standard tap *
  page20_i153
#ISCELL
  standard tap *
  page20_i154
#ISCELL
  standard tap *
  page20_i155
#ISCELL
  standard offpage *
  page20_i156
#ISCELL
  standard tap *
  page20_i157
#ISCELL
  standard tap *
  page20_i158
#CELL
  pure_quanta q_res *
  page20_i159
#ISCELL
  logical_power universal_gnd *
  page20_i16
#CELL
  pure_quanta q_res *
  page20_i160
#CELL
  pure_quanta q_res *
  page20_i161
#CELL
  pure_quanta q_res *
  page20_i162
#CELL
  pure_quanta q_res *
  page20_i163
#CELL
  pure_quanta q_res *
  page20_i164
#CELL
  pure_quanta q_res *
  page20_i165
#CELL
  pure_quanta q_res *
  page20_i166
#CELL
  pure_quanta q_res *
  page20_i167
#CELL
  pure_quanta q_res *
  page20_i168
#CELL
  pure_quanta q_res *
  page20_i169
#CELL
  pure_quanta q_res *
  page20_i17
#CELL
  pure_quanta q_res *
  page20_i170
#CELL
  pure_quanta q_res *
  page20_i171
#CELL
  pure_quanta q_res *
  page20_i172
#CELL
  pure_quanta q_res *
  page20_i173
#CELL
  pure_quanta q_res *
  page20_i174
#CELL
  pure_quanta q_res *
  page20_i175
#CELL
  pure_quanta q_res *
  page20_i176
#CELL
  pure_quanta q_res *
  page20_i177
#CELL
  pure_quanta q_res *
  page20_i178
#CELL
  pure_quanta q_res *
  page20_i179
#ISCELL
  standard offpage *
  page20_i18
#CELL
  pure_quanta q_res *
  page20_i180
#CELL
  pure_quanta q_res *
  page20_i181
#CELL
  pure_quanta q_res *
  page20_i182
#CELL
  pure_quanta q_res *
  page20_i183
#CELL
  pure_quanta q_res *
  page20_i184
#ISCELL
  logical_power universal_gnd *
  page20_i185
#CELL
  pure_quanta q_cap *
  page20_i186
#CELL
  pure_quanta q_cap *
  page20_i187
#ISCELL
  logical_power universal_gnd *
  page20_i188
#ISCELL
  logical_power universal_gnd *
  page20_i189
#CELL
  pure_quanta q_cap *
  page20_i19
#CELL
  pure_quanta q_cap *
  page20_i190
#ISCELL
  logical_power universal_gnd *
  page20_i191
#CELL
  pure_quanta q_cap *
  page20_i192
#CELL
  pure_quanta q_res *
  page20_i193
#CELL
  pure_quanta q_res *
  page20_i194
#ISCELL
  logical_power universal_power *
  page20_i195
#CELL
  pure_quanta k4a8g165wcbctd *
  page20_i196
#CELL
  pure_quanta q_cap *
  page20_i197
#CELL
  pure_quanta q_cap *
  page20_i198
#CELL
  pure_quanta q_cap *
  page20_i199
#ISCELL
  standard offpage *
  page20_i2
#ISCELL
  logical_power universal_gnd *
  page20_i20
#ISCELL
  logical_power universal_gnd *
  page20_i200
#CELL
  pure_quanta q_cap *
  page20_i21
#ISCELL
  logical_power universal_power *
  page20_i22
#CELL
  pure_quanta q_cap *
  page20_i23
#CELL
  pure_quanta q_cap *
  page20_i24
#CELL
  pure_quanta q_cap *
  page20_i25
#CELL
  pure_quanta q_res *
  page20_i27
#CELL
  pure_quanta q_res *
  page20_i28
#ISCELL
  standard offpage *
  page20_i29
#ISCELL
  logical_power universal_gnd *
  page20_i3
#ISCELL
  standard offpage *
  page20_i30
#ISCELL
  logical_power universal_gnd *
  page20_i31
#CELL
  pure_quanta q_cap *
  page20_i32
#CELL
  pure_quanta q_cap *
  page20_i33
#CELL
  pure_quanta q_cap *
  page20_i34
#ISCELL
  logical_power universal_power *
  page20_i35
#ISCELL
  logical_power universal_gnd *
  page20_i36
#ISCELL
  standard offpage *
  page20_i37
#ISCELL
  standard offpage *
  page20_i38
#ISCELL
  logical_power universal_gnd *
  page20_i39
#CELL
  pure_quanta q_cap *
  page20_i4
#ISCELL
  standard offpage *
  page20_i40
#ISCELL
  standard tap *
  page20_i41
#ISCELL
  standard tap *
  page20_i42
#ISCELL
  standard tap *
  page20_i43
#ISCELL
  standard tap *
  page20_i44
#ISCELL
  standard tap *
  page20_i45
#ISCELL
  standard tap *
  page20_i46
#ISCELL
  standard tap *
  page20_i47
#ISCELL
  standard tap *
  page20_i48
#ISCELL
  standard offpage *
  page20_i49
#CELL
  pure_quanta q_cap *
  page20_i5
#ISCELL
  standard offpage *
  page20_i50
#ISCELL
  standard offpage *
  page20_i51
#ISCELL
  standard offpage *
  page20_i52
#ISCELL
  standard offpage *
  page20_i53
#ISCELL
  standard offpage *
  page20_i54
#ISCELL
  standard offpage *
  page20_i55
#ISCELL
  standard tap *
  page20_i56
#ISCELL
  standard tap *
  page20_i57
#ISCELL
  standard tap *
  page20_i58
#ISCELL
  standard tap *
  page20_i59
#CELL
  pure_quanta q_cap *
  page20_i6
#ISCELL
  standard tap *
  page20_i60
#ISCELL
  standard tap *
  page20_i61
#ISCELL
  standard tap *
  page20_i62
#ISCELL
  standard tap *
  page20_i63
#ISCELL
  standard tap *
  page20_i64
#ISCELL
  standard tap *
  page20_i65
#ISCELL
  standard tap *
  page20_i66
#ISCELL
  standard tap *
  page20_i67
#ISCELL
  standard tap *
  page20_i68
#ISCELL
  standard tap *
  page20_i69
#CELL
  pure_quanta q_cap *
  page20_i7
#ISCELL
  standard tap *
  page20_i70
#ISCELL
  standard tap *
  page20_i71
#ISCELL
  standard tap *
  page20_i72
#ISCELL
  standard tap *
  page20_i73
#ISCELL
  standard tap *
  page20_i74
#ISCELL
  standard tap *
  page20_i75
#ISCELL
  standard tap *
  page20_i76
#ISCELL
  standard tap *
  page20_i77
#ISCELL
  standard offpage *
  page20_i78
#ISCELL
  standard offpage *
  page20_i79
#ISCELL
  logical_power universal_power *
  page20_i8
#ISCELL
  standard offpage *
  page20_i80
#ISCELL
  standard offpage *
  page20_i81
#ISCELL
  standard offpage *
  page20_i82
#ISCELL
  standard offpage *
  page20_i83
#ISCELL
  standard offpage *
  page20_i84
#CELL
  pure_quanta q_cap *
  page20_i85
#ISCELL
  standard offpage *
  page20_i86
#ISCELL
  standard offpage *
  page20_i87
#ISCELL
  standard offpage *
  page20_i88
#CELL
  pure_quanta q_res *
  page20_i89
#ISCELL
  standard offpage *
  page20_i9
#CELL
  pure_quanta q_res *
  page20_i90
#ISCELL
  logical_power universal_power *
  page20_i91
#ISCELL
  standard offpage *
  page20_i92
#ISCELL
  logical_power universal_gnd *
  page20_i93
#ISCELL
  logical_power universal_gnd *
  page20_i94
#ISCELL
  standard offpage *
  page20_i95
#ISCELL
  standard offpage *
  page20_i96
#ISCELL
  standard offpage *
  page20_i97
#ISCELL
  standard offpage *
  page20_i98
#ISCELL
  standard offpage *
  page20_i99
